(kicad_pcb
	(version 20260206)
	(generator "pcbnew")
	(generator_version "10.0")
	(general
		(thickness 1.6)
		(legacy_teardrops no)
	)
	(paper "A4")
	(title_block
		(title "Bryce Canyon_IOM_M2_16342-2_OCP.brd")
		(comment 1 "Bryce Canyon / footprints 865-871 of 1146")
	)
	(layers
		(0 "F.Cu" signal "TOP")
		(4 "In1.Cu" signal "L2GND")
		(6 "In2.Cu" signal "L3")
		(8 "In3.Cu" signal "L4VCC")
		(10 "In4.Cu" signal "L5VCC")
		(12 "In5.Cu" signal "L6")
		(14 "In6.Cu" signal "L7GND")
		(2 "B.Cu" signal "BOTTOM")
		(9 "F.Adhes" user "F.Adhesive")
		(11 "B.Adhes" user "B.Adhesive")
		(13 "F.Paste" user "Package Geometry/Pastemask Top")
		(15 "B.Paste" user "Package Geometry/Pastemask Bottom")
		(5 "F.SilkS" user "Ref Des/Silkscreen Top")
		(7 "B.SilkS" user "Ref Des/Silkscreen Bottom")
		(1 "F.Mask" user "Board Geometry/Soldermask Top")
		(3 "B.Mask" user "Board Geometry/Soldermask Bottom")
		(17 "Dwgs.User" user "User.Drawings")
		(19 "Cmts.User" user "User.Comments")
		(21 "Eco1.User" user "User.Eco1")
		(23 "Eco2.User" user "User.Eco2")
		(25 "Edge.Cuts" user "Board Geometry/Outline")
		(27 "Margin" user)
		(31 "F.CrtYd" user "Package Geometry/Place Bound Top")
		(29 "B.CrtYd" user "Package Geometry/Place Bound Bottom")
		(35 "F.Fab" user "Ref Des/Assembly Top")
		(33 "B.Fab" user "Ref Des/Assembly Bottom")
	)
	(footprint ""
		(layer "B.Cu")
		(at 125.861572 -10.822178 -90)
		(property "Reference" "R437"
			(at 0 0 90)
			(layer "B.SilkS")
			(hide yes)
			(effects
				(font
					(size 1.27 1.27)
				)
				(justify mirror)
			)
		)
		(property "Value" "100KR2F-L1-GP"
			(at -0.064008 -3.993896 270)
			(unlocked yes)
			(layer "B.Fab")
			(hide yes)
			(effects
				(font
					(size 1.016 1.016)
					(thickness 0.1524)
				)
				(justify mirror)
			)
		)
		(property "Device Type" "R402H16"
			(at -0.064008 -5.517896 270)
			(unlocked yes)
			(layer "B.Fab")
			(hide yes)
			(effects
				(font
					(size 1.016 1.016)
					(thickness 0.1524)
				)
				(justify mirror)
			)
		)
		(duplicate_pad_numbers_are_jumpers no)
		(fp_line
			(start -0.508 -0.9398)
			(end 0.508 -0.9398)
			(stroke
				(width 0.1524)
				(type default)
			)
			(layer "B.SilkS")
		)
		(fp_line
			(start 0.508 -0.9398)
			(end 0.508 0.9398)
			(stroke
				(width 0.1524)
				(type default)
			)
			(layer "B.SilkS")
		)
		(fp_rect
			(start 0.508 0.9398)
			(end -0.508 -0.9398)
			(stroke
				(width 0)
				(type default)
			)
			(fill no)
			(layer "B.CrtYd")
		)
		(fp_rect
			(start 0.508 0.9398)
			(end -0.508 -0.9398)
			(stroke
				(width 0)
				(type default)
			)
			(fill no)
			(layer "B.Fab")
		)
		(pad "1" smd custom
			(at 0 -0.4445 90)
			(size 0.1397 0.1397)
			(layers "B.Cu" "B.Mask" "B.Paste")
			(net "P12V_STBY")
			(options
				(clearance outline)
				(anchor circle)
			)
			(primitives
				(gr_poly
					(pts
						(arc
							(start -0.1778 0.2794)
							(mid -0.249642 0.249642)
							(end -0.2794 0.1778)
						)
						(arc
							(start -0.2794 -0.1778)
							(mid -0.249642 -0.249642)
							(end -0.1778 -0.2794)
						)
						(arc
							(start 0.1778 -0.2794)
							(mid 0.249642 -0.249642)
							(end 0.2794 -0.1778)
						)
						(arc
							(start 0.2794 0.1778)
							(mid 0.249642 0.249642)
							(end 0.1778 0.2794)
						)
					)
					(width 0)
					(fill yes)
				)
			)
		)
		(pad "2" smd custom
			(at 0 0.4445 90)
			(size 0.1397 0.1397)
			(layers "B.Cu" "B.Mask" "B.Paste")
			(net "MB0_P12V_PWGIN_R")
			(options
				(clearance outline)
				(anchor circle)
			)
			(primitives
				(gr_poly
					(pts
						(arc
							(start -0.1778 0.2794)
							(mid -0.249642 0.249642)
							(end -0.2794 0.1778)
						)
						(arc
							(start -0.2794 -0.1778)
							(mid -0.249642 -0.249642)
							(end -0.1778 -0.2794)
						)
						(arc
							(start 0.1778 -0.2794)
							(mid 0.249642 -0.249642)
							(end 0.2794 -0.1778)
						)
						(arc
							(start 0.2794 0.1778)
							(mid 0.249642 0.249642)
							(end 0.1778 0.2794)
						)
					)
					(width 0)
					(fill yes)
				)
			)
		)
	)
	(footprint ""
		(layer "B.Cu")
		(at 60.01004 -134.410958)
		(property "Reference" "TP206"
			(at 0 0 0)
			(layer "B.SilkS")
			(hide yes)
			(effects
				(font
					(size 1.27 1.27)
				)
				(justify mirror)
			)
		)
		(property "Value" "TPAD28-2-GP"
			(at 0.0127 -1.6637 0)
			(unlocked yes)
			(layer "B.Fab")
			(hide yes)
			(effects
				(font
					(size 1.016 1.016)
					(thickness 0.1524)
				)
				(justify mirror)
			)
		)
		(property "Device Type" "TPAD28"
			(at 0.0127 -3.1877 0)
			(unlocked yes)
			(layer "B.Fab")
			(hide yes)
			(effects
				(font
					(size 1.016 1.016)
					(thickness 0.1524)
				)
				(justify mirror)
			)
		)
		(duplicate_pad_numbers_are_jumpers no)
		(fp_poly
			(pts
				(arc
					(start 0.3556 0)
					(mid -0.3556 0)
					(end 0.3556 0)
				)
			)
			(stroke
				(width 0)
				(type default)
			)
			(fill no)
			(layer "B.CrtYd")
		)
		(fp_poly
			(pts
				(arc
					(start 0.6096 0)
					(mid -0.6096 0)
					(end 0.6096 0)
				)
			)
			(stroke
				(width 0)
				(type default)
			)
			(fill no)
			(layer "B.Fab")
		)
		(pad "1" smd circle
			(at 0 0 180)
			(size 0.7112 0.7112)
			(layers "B.Cu" "B.Mask" "B.Paste")
			(net "TP_BMC_EXT1_LED_G")
		)
	)
	(footprint ""
		(layer "B.Cu")
		(at 12.091924 -135.285988 90)
		(property "Reference" "R257"
			(at 0 0 90)
			(layer "B.SilkS")
			(hide yes)
			(effects
				(font
					(size 1.27 1.27)
				)
				(justify mirror)
			)
		)
		(property "Value" "120R2F-GP"
			(at -0.064008 -3.993896 90)
			(unlocked yes)
			(layer "B.Fab")
			(hide yes)
			(effects
				(font
					(size 1.016 1.016)
					(thickness 0.1524)
				)
				(justify mirror)
			)
		)
		(property "Device Type" "R402H16"
			(at -0.064008 -5.517896 90)
			(unlocked yes)
			(layer "B.Fab")
			(hide yes)
			(effects
				(font
					(size 1.016 1.016)
					(thickness 0.1524)
				)
				(justify mirror)
			)
		)
		(duplicate_pad_numbers_are_jumpers no)
		(fp_line
			(start 0.508 -0.9398)
			(end 0.508 0.9398)
			(stroke
				(width 0.1524)
				(type default)
			)
			(layer "B.SilkS")
		)
		(fp_line
			(start -0.508 -0.9398)
			(end 0.508 -0.9398)
			(stroke
				(width 0.1524)
				(type default)
			)
			(layer "B.SilkS")
		)
		(fp_rect
			(start 0.508 0.9398)
			(end -0.508 -0.9398)
			(stroke
				(width 0)
				(type default)
			)
			(fill no)
			(layer "B.CrtYd")
		)
		(fp_rect
			(start 0.508 0.9398)
			(end -0.508 -0.9398)
			(stroke
				(width 0)
				(type default)
			)
			(fill no)
			(layer "B.Fab")
		)
		(pad "1" smd custom
			(at 0 -0.4445 270)
			(size 0.1397 0.1397)
			(layers "B.Cu" "B.Mask" "B.Paste")
			(net "MEMA_11")
			(options
				(clearance outline)
				(anchor circle)
			)
			(primitives
				(gr_poly
					(pts
						(arc
							(start -0.1778 0.2794)
							(mid -0.249642 0.249642)
							(end -0.2794 0.1778)
						)
						(arc
							(start -0.2794 -0.1778)
							(mid -0.249642 -0.249642)
							(end -0.1778 -0.2794)
						)
						(arc
							(start 0.1778 -0.2794)
							(mid 0.249642 -0.249642)
							(end 0.2794 -0.1778)
						)
						(arc
							(start 0.2794 0.1778)
							(mid 0.249642 0.249642)
							(end 0.1778 0.2794)
						)
					)
					(width 0)
					(fill yes)
				)
			)
		)
		(pad "2" smd custom
			(at 0 0.4445 270)
			(size 0.1397 0.1397)
			(layers "B.Cu" "B.Mask" "B.Paste")
			(net "P1V2_STBY")
			(options
				(clearance outline)
				(anchor circle)
			)
			(primitives
				(gr_poly
					(pts
						(arc
							(start -0.1778 0.2794)
							(mid -0.249642 0.249642)
							(end -0.2794 0.1778)
						)
						(arc
							(start -0.2794 -0.1778)
							(mid -0.249642 -0.249642)
							(end -0.1778 -0.2794)
						)
						(arc
							(start 0.1778 -0.2794)
							(mid 0.249642 -0.249642)
							(end 0.2794 -0.1778)
						)
						(arc
							(start 0.2794 0.1778)
							(mid 0.249642 0.249642)
							(end 0.1778 0.2794)
						)
					)
					(width 0)
					(fill yes)
				)
			)
		)
	)
	(footprint ""
		(layer "B.Cu")
		(at 51.03114 -142.61846 180)
		(property "Reference" "R357"
			(at 0 0 0)
			(layer "B.SilkS")
			(hide yes)
			(effects
				(font
					(size 1.27 1.27)
				)
				(justify mirror)
			)
		)
		(property "Value" "4K7R2F-GP"
			(at -0.064008 -3.993896 180)
			(unlocked yes)
			(layer "B.Fab")
			(hide yes)
			(effects
				(font
					(size 1.016 1.016)
					(thickness 0.1524)
				)
				(justify mirror)
			)
		)
		(property "Device Type" "R402H16"
			(at -0.064008 -5.517896 180)
			(unlocked yes)
			(layer "B.Fab")
			(hide yes)
			(effects
				(font
					(size 1.016 1.016)
					(thickness 0.1524)
				)
				(justify mirror)
			)
		)
		(duplicate_pad_numbers_are_jumpers no)
		(fp_line
			(start 0.508 -0.9398)
			(end 0.508 0.9398)
			(stroke
				(width 0.1524)
				(type default)
			)
			(layer "B.SilkS")
		)
		(fp_line
			(start -0.508 -0.9398)
			(end 0.508 -0.9398)
			(stroke
				(width 0.1524)
				(type default)
			)
			(layer "B.SilkS")
		)
		(fp_rect
			(start 0.508 0.9398)
			(end -0.508 -0.9398)
			(stroke
				(width 0)
				(type default)
			)
			(fill no)
			(layer "B.CrtYd")
		)
		(fp_rect
			(start 0.508 0.9398)
			(end -0.508 -0.9398)
			(stroke
				(width 0)
				(type default)
			)
			(fill no)
			(layer "B.Fab")
		)
		(pad "1" smd custom
			(at 0 -0.4445)
			(size 0.1397 0.1397)
			(layers "B.Cu" "B.Mask" "B.Paste")
			(net "P3V3_STBY")
			(options
				(clearance outline)
				(anchor circle)
			)
			(primitives
				(gr_poly
					(pts
						(arc
							(start -0.1778 0.2794)
							(mid -0.249642 0.249642)
							(end -0.2794 0.1778)
						)
						(arc
							(start -0.2794 -0.1778)
							(mid -0.249642 -0.249642)
							(end -0.1778 -0.2794)
						)
						(arc
							(start 0.1778 -0.2794)
							(mid 0.249642 -0.249642)
							(end 0.2794 -0.1778)
						)
						(arc
							(start 0.2794 0.1778)
							(mid 0.249642 0.249642)
							(end 0.1778 0.2794)
						)
					)
					(width 0)
					(fill yes)
				)
			)
		)
		(pad "2" smd custom
			(at 0 0.4445)
			(size 0.1397 0.1397)
			(layers "B.Cu" "B.Mask" "B.Paste")
			(net "JTAG_BMC_TRST_N")
			(options
				(clearance outline)
				(anchor circle)
			)
			(primitives
				(gr_poly
					(pts
						(arc
							(start -0.1778 0.2794)
							(mid -0.249642 0.249642)
							(end -0.2794 0.1778)
						)
						(arc
							(start -0.2794 -0.1778)
							(mid -0.249642 -0.249642)
							(end -0.1778 -0.2794)
						)
						(arc
							(start 0.1778 -0.2794)
							(mid 0.249642 -0.249642)
							(end 0.2794 -0.1778)
						)
						(arc
							(start 0.2794 0.1778)
							(mid 0.249642 0.249642)
							(end 0.1778 0.2794)
						)
					)
					(width 0)
					(fill yes)
				)
			)
		)
	)
	(footprint ""
		(layer "B.Cu")
		(at 86.520274 -98.697796 180)
		(property "Reference" "Q25"
			(at 0 0 0)
			(layer "B.SilkS")
			(hide yes)
			(effects
				(font
					(size 1.27 1.27)
				)
				(justify mirror)
			)
		)
		(property "Value" "2N7002K-1-GP"
			(at -0.127 -8.9662 180)
			(unlocked yes)
			(layer "B.Fab")
			(hide yes)
			(effects
				(font
					(size 1.016 1.016)
					(thickness 0.1524)
				)
				(justify mirror)
			)
		)
		(property "Device Type" "SOT23DGS2D4H44"
			(at -0.127 -10.4902 180)
			(unlocked yes)
			(layer "B.Fab")
			(hide yes)
			(effects
				(font
					(size 1.016 1.016)
					(thickness 0.1524)
				)
				(justify mirror)
			)
		)
		(duplicate_pad_numbers_are_jumpers no)
		(fp_line
			(start 1.651 1.778)
			(end -1.651 1.778)
			(stroke
				(width 0.1524)
				(type default)
			)
			(layer "B.SilkS")
		)
		(fp_line
			(start 1.651 -1.778)
			(end 1.651 1.778)
			(stroke
				(width 0.1524)
				(type default)
			)
			(layer "B.SilkS")
		)
		(fp_line
			(start -1.651 1.778)
			(end -1.651 -1.778)
			(stroke
				(width 0.1524)
				(type default)
			)
			(layer "B.SilkS")
		)
		(fp_line
			(start -1.651 -1.778)
			(end 1.651 -1.778)
			(stroke
				(width 0.1524)
				(type default)
			)
			(layer "B.SilkS")
		)
		(fp_poly
			(pts
				(xy 1.778 1.8796) (xy 1.778 -1.8796) (xy -1.778 -1.8796) (xy -1.778 1.8796)
			)
			(stroke
				(width 0)
				(type default)
			)
			(fill no)
			(layer "B.CrtYd")
		)
		(fp_poly
			(pts
				(xy 1.778 1.8796) (xy 1.778 -1.8796) (xy -1.778 -1.8796) (xy -1.778 1.8796)
			)
			(stroke
				(width 0)
				(type default)
			)
			(fill no)
			(layer "B.Fab")
		)
		(pad "D" smd custom
			(at 0 -0.9525)
			(size 0.1905 0.1905)
			(layers "B.Cu" "B.Mask" "B.Paste")
			(net "CONN_A_PRSNTA")
			(options
				(clearance outline)
				(anchor circle)
			)
			(primitives
				(gr_poly
					(pts
						(arc
							(start -0.1778 -0.5715)
							(mid -0.321484 -0.511984)
							(end -0.381 -0.3683)
						)
						(arc
							(start -0.381 0.3683)
							(mid -0.321484 0.511984)
							(end -0.1778 0.5715)
						)
						(arc
							(start 0.1778 0.5715)
							(mid 0.321484 0.511984)
							(end 0.381 0.3683)
						)
						(arc
							(start 0.381 -0.3683)
							(mid 0.321484 -0.511984)
							(end 0.1778 -0.5715)
						)
					)
					(width 0)
					(fill yes)
				)
			)
		)
		(pad "G" smd custom
			(at 0.98425 0.9525)
			(size 0.1905 0.1905)
			(layers "B.Cu" "B.Mask" "B.Paste")
			(net "MEZZ_A_PRSNT_120_N")
			(options
				(clearance outline)
				(anchor circle)
			)
			(primitives
				(gr_poly
					(pts
						(arc
							(start -0.1778 -0.5715)
							(mid -0.321484 -0.511984)
							(end -0.381 -0.3683)
						)
						(arc
							(start -0.381 0.3683)
							(mid -0.321484 0.511984)
							(end -0.1778 0.5715)
						)
						(arc
							(start 0.1778 0.5715)
							(mid 0.321484 0.511984)
							(end 0.381 0.3683)
						)
						(arc
							(start 0.381 -0.3683)
							(mid 0.321484 -0.511984)
							(end 0.1778 -0.5715)
						)
					)
					(width 0)
					(fill yes)
				)
			)
		)
		(pad "S" smd custom
			(at -0.98425 0.9525)
			(size 0.1905 0.1905)
			(layers "B.Cu" "B.Mask" "B.Paste")
			(net "GND")
			(options
				(clearance outline)
				(anchor circle)
			)
			(primitives
				(gr_poly
					(pts
						(arc
							(start -0.1778 -0.5715)
							(mid -0.321484 -0.511984)
							(end -0.381 -0.3683)
						)
						(arc
							(start -0.381 0.3683)
							(mid -0.321484 0.511984)
							(end -0.1778 0.5715)
						)
						(arc
							(start 0.1778 0.5715)
							(mid 0.321484 0.511984)
							(end 0.381 0.3683)
						)
						(arc
							(start 0.381 -0.3683)
							(mid 0.321484 -0.511984)
							(end 0.1778 -0.5715)
						)
					)
					(width 0)
					(fill yes)
				)
			)
		)
	)
	(footprint ""
		(layer "B.Cu")
		(at 52.2478 -161.1376 -90)
		(property "Reference" "C627"
			(at 0 0 90)
			(layer "B.SilkS")
			(hide yes)
			(effects
				(font
					(size 1.27 1.27)
				)
				(justify mirror)
			)
		)
		(property "Value" "SCD1U25V2KX-2-GP"
			(at -1.1811 -2.7051 270)
			(unlocked yes)
			(layer "B.Fab")
			(hide yes)
			(effects
				(font
					(size 1.016 1.016)
					(thickness 0.1524)
				)
				(justify mirror)
			)
		)
		(property "Device Type" "C402H22"
			(at -1.1811 -4.2291 270)
			(unlocked yes)
			(layer "B.Fab")
			(hide yes)
			(effects
				(font
					(size 1.016 1.016)
					(thickness 0.1524)
				)
				(justify mirror)
			)
		)
		(duplicate_pad_numbers_are_jumpers no)
		(fp_rect
			(start 0.4318 0.9525)
			(end -0.4318 -0.9525)
			(stroke
				(width 0)
				(type default)
			)
			(fill no)
			(layer "B.CrtYd")
		)
		(fp_rect
			(start 0.4318 0.9525)
			(end -0.4318 -0.9525)
			(stroke
				(width 0)
				(type default)
			)
			(fill no)
			(layer "B.Fab")
		)
		(pad "1" smd custom
			(at 0 -0.4445 90)
			(size 0.1524 0.1524)
			(layers "B.Cu" "B.Mask" "B.Paste")
			(net "ADC_P3V3_M2")
			(options
				(clearance outline)
				(anchor circle)
			)
			(primitives
				(gr_poly
					(pts
						(arc
							(start 0.3048 0.2032)
							(mid 0.275042 0.275042)
							(end 0.2032 0.3048)
						)
						(arc
							(start -0.2032 0.3048)
							(mid -0.275042 0.275042)
							(end -0.3048 0.2032)
						)
						(arc
							(start -0.3048 -0.2032)
							(mid -0.275042 -0.275042)
							(end -0.2032 -0.3048)
						)
						(arc
							(start 0.2032 -0.3048)
							(mid 0.275042 -0.275042)
							(end 0.3048 -0.2032)
						)
					)
					(width 0)
					(fill yes)
				)
			)
		)
		(pad "2" smd custom
			(at 0 0.4445 90)
			(size 0.1524 0.1524)
			(layers "B.Cu" "B.Mask" "B.Paste")
			(net "GND")
			(options
				(clearance outline)
				(anchor circle)
			)
			(primitives
				(gr_poly
					(pts
						(arc
							(start 0.3048 0.2032)
							(mid 0.275042 0.275042)
							(end 0.2032 0.3048)
						)
						(arc
							(start -0.2032 0.3048)
							(mid -0.275042 0.275042)
							(end -0.3048 0.2032)
						)
						(arc
							(start -0.3048 -0.2032)
							(mid -0.275042 -0.275042)
							(end -0.2032 -0.3048)
						)
						(arc
							(start 0.2032 -0.3048)
							(mid 0.275042 -0.275042)
							(end 0.3048 -0.2032)
						)
					)
					(width 0)
					(fill yes)
				)
			)
		)
	)
	(footprint ""
		(layer "B.Cu")
		(at 174.9552 -126.113286 90)
		(property "Reference" "C623"
			(at 0 0 90)
			(layer "B.SilkS")
			(hide yes)
			(effects
				(font
					(size 1.27 1.27)
				)
				(justify mirror)
			)
		)
		(property "Value" "SCD1U16V2KX-3GP"
			(at -1.1811 -2.7051 90)
			(unlocked yes)
			(layer "B.Fab")
			(hide yes)
			(effects
				(font
					(size 1.016 1.016)
					(thickness 0.1524)
				)
				(justify mirror)
			)
		)
		(property "Device Type" "C402H22"
			(at -1.1811 -4.2291 90)
			(unlocked yes)
			(layer "B.Fab")
			(hide yes)
			(effects
				(font
					(size 1.016 1.016)
					(thickness 0.1524)
				)
				(justify mirror)
			)
		)
		(duplicate_pad_numbers_are_jumpers no)
		(fp_rect
			(start 0.4318 0.9525)
			(end -0.4318 -0.9525)
			(stroke
				(width 0)
				(type default)
			)
			(fill no)
			(layer "B.CrtYd")
		)
		(fp_rect
			(start 0.4318 0.9525)
			(end -0.4318 -0.9525)
			(stroke
				(width 0)
				(type default)
			)
			(fill no)
			(layer "B.Fab")
		)
		(pad "1" smd custom
			(at 0 -0.4445 270)
			(size 0.1524 0.1524)
			(layers "B.Cu" "B.Mask" "B.Paste")
			(net "P3V3_M2")
			(options
				(clearance outline)
				(anchor circle)
			)
			(primitives
				(gr_poly
					(pts
						(arc
							(start 0.3048 0.2032)
							(mid 0.275042 0.275042)
							(end 0.2032 0.3048)
						)
						(arc
							(start -0.2032 0.3048)
							(mid -0.275042 0.275042)
							(end -0.3048 0.2032)
						)
						(arc
							(start -0.3048 -0.2032)
							(mid -0.275042 -0.275042)
							(end -0.2032 -0.3048)
						)
						(arc
							(start 0.2032 -0.3048)
							(mid 0.275042 -0.275042)
							(end 0.3048 -0.2032)
						)
					)
					(width 0)
					(fill yes)
				)
			)
		)
		(pad "2" smd custom
			(at 0 0.4445 270)
			(size 0.1524 0.1524)
			(layers "B.Cu" "B.Mask" "B.Paste")
			(net "GND")
			(options
				(clearance outline)
				(anchor circle)
			)
			(primitives
				(gr_poly
					(pts
						(arc
							(start 0.3048 0.2032)
							(mid 0.275042 0.275042)
							(end 0.2032 0.3048)
						)
						(arc
							(start -0.2032 0.3048)
							(mid -0.275042 0.275042)
							(end -0.3048 0.2032)
						)
						(arc
							(start -0.3048 -0.2032)
							(mid -0.275042 -0.275042)
							(end -0.2032 -0.3048)
						)
						(arc
							(start 0.2032 -0.3048)
							(mid 0.275042 -0.275042)
							(end 0.3048 -0.2032)
						)
					)
					(width 0)
					(fill yes)
				)
			)
		)
	)
)
